# BASEBOARD_FAB2 (Tioga Pass) — schematic netlist excerpt (pin names and nets, part order shuffled) for the footprints in the layout excerpt that follows; sources: Cadence DE-HDL packaged netlist, KiCad conversion of Wiwynn_Tioga_Pass_MB.brd

R2U7  RES  20.0 1% CHIP  pkg 0402  page 159 : A = SMB_OCP_FRU_STBY_LVC3_SCL_R ; B = SMB_OCP_FRU_STBY_LVC3_SCL
C25W17  SC1U16V3KX-2GP  10%  pkg SMD-BCG  page 151 : \1\ = P1V2_AUX_BMC ; \2\ = GND
C6R4  CAP  10UF 16V 10% X6S  pkg 0805  page 202 : A = VR_FET_SW_P12V_STBY_PVCCIN_CPU0 ; B = GND

(kicad_pcb
	(version 20260206)
	(generator "pcbnew")
	(generator_version "10.0")
	(general
		(thickness 1.6)
		(legacy_teardrops no)
	)
	(paper "A4")
	(title_block
		(title "Wiwynn_Tioga_Pass_MB.brd")
		(comment 1 "Tioga Pass / footprints 2969-2971 of 4770")
	)
	(layers
		(0 "F.Cu" signal "TOP")
		(4 "In1.Cu" signal "L2GND")
		(6 "In2.Cu" signal "L3")
		(8 "In3.Cu" signal "L4GND")
		(10 "In4.Cu" signal "L5")
		(12 "In5.Cu" signal "L6GND")
		(14 "In6.Cu" signal "L7VCC")
		(16 "In7.Cu" signal "L8VCC")
		(18 "In8.Cu" signal "L9GND")
		(20 "In9.Cu" signal "L10")
		(22 "In10.Cu" signal "L11GND")
		(24 "In11.Cu" signal "L12")
		(26 "In12.Cu" signal "L13GND")
		(2 "B.Cu" signal "BOTTOM")
		(9 "F.Adhes" user "F.Adhesive")
		(11 "B.Adhes" user "B.Adhesive")
		(13 "F.Paste" user "Package Geometry/Pastemask Top")
		(15 "B.Paste" user "Package Geometry/Pastemask Bottom")
		(5 "F.SilkS" user "Ref Des/Silkscreen Top")
		(7 "B.SilkS" user "Ref Des/Silkscreen Bottom")
		(1 "F.Mask" user "Board Geometry/Soldermask Top")
		(3 "B.Mask" user "Board Geometry/Soldermask Bottom")
		(17 "Dwgs.User" user "User.Drawings")
		(19 "Cmts.User" user "User.Comments")
		(21 "Eco1.User" user "User.Eco1")
		(23 "Eco2.User" user "User.Eco2")
		(25 "Edge.Cuts" user "Board Geometry/Outline")
		(27 "Margin" user)
		(31 "F.CrtYd" user "Package Geometry/Place Bound Top")
		(29 "B.CrtYd" user "Package Geometry/Place Bound Bottom")
		(35 "F.Fab" user "Ref Des/Assembly Top")
		(33 "B.Fab" user "Ref Des/Assembly Bottom")
	)
	(footprint ""
		(layer "B.Cu")
		(at 402.4503 -38.7604 -90)
		(property "Reference" "R2U7"
			(at 0 0 90)
			(layer "B.SilkS")
			(hide yes)
			(effects
				(font
					(size 1.27 1.27)
				)
				(justify mirror)
			)
		)
		(property "Value" ""
			(at 0 0 90)
			(layer "B.Fab")
			(effects
				(font
					(size 1.27 1.27)
				)
				(justify mirror)
			)
		)
		(duplicate_pad_numbers_are_jumpers no)
		(fp_poly
			(pts
				(xy 0.2794 -0.1016) (xy -0.2794 -0.1016) (xy -0.2794 0.9906) (xy 0.2794 0.9906)
			)
			(stroke
				(width 0)
				(type default)
			)
			(fill no)
			(layer "B.CrtYd")
		)
		(fp_line
			(start -0.2794 0.9906)
			(end -0.2794 -0.1016)
			(stroke
				(width 0.1)
				(type default)
			)
			(layer "B.Fab")
		)
		(fp_line
			(start 0.2794 0.9906)
			(end -0.2794 0.9906)
			(stroke
				(width 0.1)
				(type default)
			)
			(layer "B.Fab")
		)
		(fp_line
			(start -0.2794 -0.1016)
			(end 0.2794 -0.1016)
			(stroke
				(width 0.1)
				(type default)
			)
			(layer "B.Fab")
		)
		(fp_line
			(start 0.2794 -0.1016)
			(end 0.2794 0.9906)
			(stroke
				(width 0.1)
				(type default)
			)
			(layer "B.Fab")
		)
		(pad "1" smd rect
			(at 0 0 90)
			(size 0.508 0.508)
			(layers "B.Cu" "B.Mask" "B.Paste")
			(net "SMB_OCP_FRU_STBY_LVC3_SCL_R")
		)
		(pad "2" smd rect
			(at 0 0.889 90)
			(size 0.508 0.508)
			(layers "B.Cu" "B.Mask" "B.Paste")
			(net "SMB_OCP_FRU_STBY_LVC3_SCL")
		)
		(zone
			(layer "B.Cu")
			(hatch none 0.5)
			(connect_pads
				(clearance 0)
			)
			(min_thickness 0.25)
			(keepout
				(tracks not_allowed)
				(vias allowed)
				(pads allowed)
				(copperpour not_allowed)
				(footprints allowed)
			)
			(placement
				(enabled no)
				(sheetname "")
			)
			(fill
				(thermal_gap 0.5)
				(thermal_bridge_width 0.5)
				(island_removal_mode 0)
			)
			(polygon
				(pts
					(xy 401.8153 -38.5064) (xy 401.8153 -39.0144) (xy 402.1963 -39.0144) (xy 402.1963 -38.5064)
				)
			)
		)
		(zone
			(layer "B.Cu")
			(hatch none 0.5)
			(connect_pads
				(clearance 0)
			)
			(min_thickness 0.25)
			(keepout
				(tracks allowed)
				(vias not_allowed)
				(pads allowed)
				(copperpour not_allowed)
				(footprints allowed)
			)
			(placement
				(enabled no)
				(sheetname "")
			)
			(fill
				(thermal_gap 0.5)
				(thermal_bridge_width 0.5)
				(island_removal_mode 0)
			)
			(polygon
				(pts
					(xy 402.1963 -38.5064) (xy 402.1963 -39.0144) (xy 401.8153 -39.0144) (xy 401.8153 -38.5064)
				)
			)
		)
	)
	(footprint ""
		(layer "B.Cu")
		(at 197.848728 -64.676782 90)
		(property "Reference" "C6R4"
			(at 0 0 90)
			(layer "B.SilkS")
			(hide yes)
			(effects
				(font
					(size 1.27 1.27)
				)
				(justify mirror)
			)
		)
		(property "Value" ""
			(at 0 0 90)
			(layer "B.Fab")
			(effects
				(font
					(size 1.27 1.27)
				)
				(justify mirror)
			)
		)
		(duplicate_pad_numbers_are_jumpers no)
		(fp_rect
			(start -0.7239 -0.2159)
			(end 0.7239 1.9939)
			(stroke
				(width 0)
				(type default)
			)
			(fill no)
			(layer "B.CrtYd")
		)
		(fp_line
			(start 0.7239 -0.2159)
			(end 0.7239 1.9939)
			(stroke
				(width 0.1)
				(type default)
			)
			(layer "B.Fab")
		)
		(fp_line
			(start -0.7239 -0.2159)
			(end 0.7239 -0.2159)
			(stroke
				(width 0.1)
				(type default)
			)
			(layer "B.Fab")
		)
		(fp_line
			(start 0.7239 1.9939)
			(end -0.7239 1.9939)
			(stroke
				(width 0.1)
				(type default)
			)
			(layer "B.Fab")
		)
		(fp_line
			(start -0.7239 1.9939)
			(end -0.7239 -0.2159)
			(stroke
				(width 0.1)
				(type default)
			)
			(layer "B.Fab")
		)
		(pad "1" smd rect
			(at 0 0 270)
			(size 1.27 1.016)
			(layers "B.Cu" "B.Mask" "B.Paste")
			(net "VR_FET_SW_P12V_STBY_PVCCIN_CPU0")
		)
		(pad "2" smd rect
			(at 0 1.778 270)
			(size 1.27 1.016)
			(layers "B.Cu" "B.Mask" "B.Paste")
			(net "GND")
		)
		(zone
			(layer "B.Cu")
			(hatch none 0.5)
			(connect_pads
				(clearance 0)
			)
			(min_thickness 0.25)
			(keepout
				(tracks not_allowed)
				(vias allowed)
				(pads allowed)
				(copperpour not_allowed)
				(footprints allowed)
			)
			(placement
				(enabled no)
				(sheetname "")
			)
			(fill
				(thermal_gap 0.5)
				(thermal_bridge_width 0.5)
				(island_removal_mode 0)
			)
			(polygon
				(pts
					(xy 198.356728 -64.041782) (xy 199.118728 -64.041782) (xy 199.118728 -65.311782) (xy 198.356728 -65.311782)
				)
			)
		)
	)
	(footprint ""
		(layer "B.Cu")
		(at 450.317362 -29.314648)
		(property "Reference" "C25W17"
			(at 0 0 0)
			(layer "B.SilkS")
			(hide yes)
			(effects
				(font
					(size 1.27 1.27)
				)
				(justify mirror)
			)
		)
		(property "Value" "*"
			(at 0 -2.9337 0)
			(unlocked yes)
			(layer "B.Fab")
			(hide yes)
			(effects
				(font
					(size 1.27 1.016)
					(thickness 0.1524)
				)
				(justify mirror)
			)
		)
		(property "Device Type" "SC1U16V3KX-2GP_SMD-BCG-SC1U16VA"
			(at 0 -4.4577 0)
			(unlocked yes)
			(layer "B.Fab")
			(hide yes)
			(effects
				(font
					(size 1.27 1.016)
					(thickness 0.1524)
				)
				(justify mirror)
			)
		)
		(duplicate_pad_numbers_are_jumpers no)
		(fp_line
			(start -0.508 0)
			(end 0.508 0)
			(stroke
				(width 0.2032)
				(type default)
			)
			(layer "B.SilkS")
		)
		(fp_rect
			(start 0.5842 1.3335)
			(end -0.5842 -1.3335)
			(stroke
				(width 0)
				(type default)
			)
			(fill no)
			(layer "B.CrtYd")
		)
		(fp_rect
			(start 0.5842 1.3335)
			(end -0.5842 -1.3335)
			(stroke
				(width 0)
				(type default)
			)
			(fill no)
			(layer "B.Fab")
		)
		(pad "1" smd custom
			(at 0 -0.762 180)
			(size 0.2159 0.2159)
			(layers "B.Cu" "B.Mask" "B.Paste")
			(net "P1V2_AUX_BMC")
			(options
				(clearance outline)
				(anchor circle)
			)
			(primitives
				(gr_poly
					(pts
						(arc
							(start -0.3302 0.4318)
							(mid -0.402042 0.402042)
							(end -0.4318 0.3302)
						)
						(arc
							(start -0.4318 -0.3302)
							(mid -0.402042 -0.402042)
							(end -0.3302 -0.4318)
						)
						(arc
							(start 0.3302 -0.4318)
							(mid 0.402042 -0.402042)
							(end 0.4318 -0.3302)
						)
						(arc
							(start 0.4318 0.3302)
							(mid 0.402042 0.402042)
							(end 0.3302 0.4318)
						)
					)
					(width 0)
					(fill yes)
				)
			)
		)
		(pad "2" smd custom
			(at 0 0.762 180)
			(size 0.2159 0.2159)
			(layers "B.Cu" "B.Mask" "B.Paste")
			(net "GND")
			(options
				(clearance outline)
				(anchor circle)
			)
			(primitives
				(gr_poly
					(pts
						(arc
							(start -0.3302 0.4318)
							(mid -0.402042 0.402042)
							(end -0.4318 0.3302)
						)
						(arc
							(start -0.4318 -0.3302)
							(mid -0.402042 -0.402042)
							(end -0.3302 -0.4318)
						)
						(arc
							(start 0.3302 -0.4318)
							(mid 0.402042 -0.402042)
							(end 0.4318 -0.3302)
						)
						(arc
							(start 0.4318 0.3302)
							(mid 0.402042 0.402042)
							(end 0.3302 0.4318)
						)
					)
					(width 0)
					(fill yes)
				)
			)
		)
	)
)
